(kicad_pcb
	(version 20260206)
	(generator "pcbnew")
	(generator_version "10.0")
	(general
		(thickness 1.6)
		(legacy_teardrops no)
	)
	(paper "A4")
	(title_block
		(title "Wiwynn_Tioga_Pass_MB.brd")
		(comment 1 "Tioga Pass / footprints 2310-2316 of 4770")
	)
	(layers
		(0 "F.Cu" signal "TOP")
		(4 "In1.Cu" signal "L2GND")
		(6 "In2.Cu" signal "L3")
		(8 "In3.Cu" signal "L4GND")
		(10 "In4.Cu" signal "L5")
		(12 "In5.Cu" signal "L6GND")
		(14 "In6.Cu" signal "L7VCC")
		(16 "In7.Cu" signal "L8VCC")
		(18 "In8.Cu" signal "L9GND")
		(20 "In9.Cu" signal "L10")
		(22 "In10.Cu" signal "L11GND")
		(24 "In11.Cu" signal "L12")
		(26 "In12.Cu" signal "L13GND")
		(2 "B.Cu" signal "BOTTOM")
		(9 "F.Adhes" user "F.Adhesive")
		(11 "B.Adhes" user "B.Adhesive")
		(13 "F.Paste" user "Package Geometry/Pastemask Top")
		(15 "B.Paste" user "Package Geometry/Pastemask Bottom")
		(5 "F.SilkS" user "Ref Des/Silkscreen Top")
		(7 "B.SilkS" user "Ref Des/Silkscreen Bottom")
		(1 "F.Mask" user "Board Geometry/Soldermask Top")
		(3 "B.Mask" user "Board Geometry/Soldermask Bottom")
		(17 "Dwgs.User" user "User.Drawings")
		(19 "Cmts.User" user "User.Comments")
		(21 "Eco1.User" user "User.Eco1")
		(23 "Eco2.User" user "User.Eco2")
		(25 "Edge.Cuts" user "Board Geometry/Outline")
		(27 "Margin" user)
		(31 "F.CrtYd" user "Package Geometry/Place Bound Top")
		(29 "B.CrtYd" user "Package Geometry/Place Bound Bottom")
		(35 "F.Fab" user "Ref Des/Assembly Top")
		(33 "B.Fab" user "Ref Des/Assembly Bottom")
	)
	(footprint ""
		(layer "F.Cu")
		(at 417.9951 -88.5825)
		(property "Reference" "R2P4"
			(at 0 0 0)
			(layer "F.SilkS")
			(hide yes)
			(effects
				(font
					(size 1.27 1.27)
				)
			)
		)
		(property "Value" ""
			(at 0 0 0)
			(layer "F.Fab")
			(effects
				(font
					(size 1.27 1.27)
				)
			)
		)
		(duplicate_pad_numbers_are_jumpers no)
		(fp_poly
			(pts
				(xy -0.2794 -0.1016) (xy 0.2794 -0.1016) (xy 0.2794 0.9906) (xy -0.2794 0.9906)
			)
			(stroke
				(width 0)
				(type default)
			)
			(fill no)
			(layer "F.CrtYd")
		)
		(fp_line
			(start -0.2794 -0.1016)
			(end -0.2794 0.9906)
			(stroke
				(width 0.1)
				(type default)
			)
			(layer "F.Fab")
		)
		(fp_line
			(start -0.2794 0.9906)
			(end 0.2794 0.9906)
			(stroke
				(width 0.1)
				(type default)
			)
			(layer "F.Fab")
		)
		(fp_line
			(start 0.2794 -0.1016)
			(end -0.2794 -0.1016)
			(stroke
				(width 0.1)
				(type default)
			)
			(layer "F.Fab")
		)
		(fp_line
			(start 0.2794 0.9906)
			(end 0.2794 -0.1016)
			(stroke
				(width 0.1)
				(type default)
			)
			(layer "F.Fab")
		)
		(pad "1" smd rect
			(at 0 0)
			(size 0.508 0.508)
			(layers "F.Cu" "F.Mask" "F.Paste")
			(net "IRQ_FORCE_NM_THROTTLE_R_N")
		)
		(pad "2" smd rect
			(at 0 0.889)
			(size 0.508 0.508)
			(layers "F.Cu" "F.Mask" "F.Paste")
			(net "IRQ_FORCE_NM_THROTTLE_N")
		)
		(zone
			(layer "F.Cu")
			(hatch none 0.5)
			(connect_pads
				(clearance 0)
			)
			(min_thickness 0.25)
			(keepout
				(tracks allowed)
				(vias not_allowed)
				(pads allowed)
				(copperpour not_allowed)
				(footprints allowed)
			)
			(placement
				(enabled no)
				(sheetname "")
			)
			(fill
				(thermal_gap 0.5)
				(thermal_bridge_width 0.5)
				(island_removal_mode 0)
			)
			(polygon
				(pts
					(xy 417.7411 -88.3285) (xy 418.2491 -88.3285) (xy 418.2491 -87.9475) (xy 417.7411 -87.9475)
				)
			)
		)
		(zone
			(layer "F.Cu")
			(hatch none 0.5)
			(connect_pads
				(clearance 0)
			)
			(min_thickness 0.25)
			(keepout
				(tracks not_allowed)
				(vias allowed)
				(pads allowed)
				(copperpour not_allowed)
				(footprints allowed)
			)
			(placement
				(enabled no)
				(sheetname "")
			)
			(fill
				(thermal_gap 0.5)
				(thermal_bridge_width 0.5)
				(island_removal_mode 0)
			)
			(polygon
				(pts
					(xy 417.7411 -87.9475) (xy 418.2491 -87.9475) (xy 418.2491 -88.3285) (xy 417.7411 -88.3285)
				)
			)
		)
	)
	(footprint ""
		(layer "F.Cu")
		(at 110.7694 -83.8962)
		(property "Reference" "R3D2"
			(at 0 0 0)
			(layer "F.SilkS")
			(hide yes)
			(effects
				(font
					(size 1.27 1.27)
				)
			)
		)
		(property "Value" ""
			(at 0 0 0)
			(layer "F.Fab")
			(effects
				(font
					(size 1.27 1.27)
				)
			)
		)
		(duplicate_pad_numbers_are_jumpers no)
		(fp_poly
			(pts
				(xy -0.2794 -0.1016) (xy 0.2794 -0.1016) (xy 0.2794 0.9906) (xy -0.2794 0.9906)
			)
			(stroke
				(width 0)
				(type default)
			)
			(fill no)
			(layer "F.CrtYd")
		)
		(fp_line
			(start -0.2794 -0.1016)
			(end -0.2794 0.9906)
			(stroke
				(width 0.1)
				(type default)
			)
			(layer "F.Fab")
		)
		(fp_line
			(start -0.2794 0.9906)
			(end 0.2794 0.9906)
			(stroke
				(width 0.1)
				(type default)
			)
			(layer "F.Fab")
		)
		(fp_line
			(start 0.2794 -0.1016)
			(end -0.2794 -0.1016)
			(stroke
				(width 0.1)
				(type default)
			)
			(layer "F.Fab")
		)
		(fp_line
			(start 0.2794 0.9906)
			(end 0.2794 -0.1016)
			(stroke
				(width 0.1)
				(type default)
			)
			(layer "F.Fab")
		)
		(pad "1" smd rect
			(at 0 0)
			(size 0.508 0.508)
			(layers "F.Cu" "F.Mask" "F.Paste")
			(net "A_CPU1_KLM_RCOMP1")
		)
		(pad "2" smd rect
			(at 0 0.889)
			(size 0.508 0.508)
			(layers "F.Cu" "F.Mask" "F.Paste")
			(net "GND")
		)
		(zone
			(layer "F.Cu")
			(hatch none 0.5)
			(connect_pads
				(clearance 0)
			)
			(min_thickness 0.25)
			(keepout
				(tracks allowed)
				(vias not_allowed)
				(pads allowed)
				(copperpour not_allowed)
				(footprints allowed)
			)
			(placement
				(enabled no)
				(sheetname "")
			)
			(fill
				(thermal_gap 0.5)
				(thermal_bridge_width 0.5)
				(island_removal_mode 0)
			)
			(polygon
				(pts
					(xy 110.5154 -83.6422) (xy 111.0234 -83.6422) (xy 111.0234 -83.2612) (xy 110.5154 -83.2612)
				)
			)
		)
		(zone
			(layer "F.Cu")
			(hatch none 0.5)
			(connect_pads
				(clearance 0)
			)
			(min_thickness 0.25)
			(keepout
				(tracks not_allowed)
				(vias allowed)
				(pads allowed)
				(copperpour not_allowed)
				(footprints allowed)
			)
			(placement
				(enabled no)
				(sheetname "")
			)
			(fill
				(thermal_gap 0.5)
				(thermal_bridge_width 0.5)
				(island_removal_mode 0)
			)
			(polygon
				(pts
					(xy 110.5154 -83.2612) (xy 111.0234 -83.2612) (xy 111.0234 -83.6422) (xy 110.5154 -83.6422)
				)
			)
		)
	)
	(footprint ""
		(layer "F.Cu")
		(at 401.701 -34.426652 90)
		(property "Reference" "R8C15"
			(at 0 0 90)
			(layer "F.SilkS")
			(hide yes)
			(effects
				(font
					(size 1.27 1.27)
				)
			)
		)
		(property "Value" ""
			(at 0 0 90)
			(layer "F.Fab")
			(effects
				(font
					(size 1.27 1.27)
				)
			)
		)
		(duplicate_pad_numbers_are_jumpers no)
		(fp_poly
			(pts
				(xy -0.2794 -0.1016) (xy 0.2794 -0.1016) (xy 0.2794 0.9906) (xy -0.2794 0.9906)
			)
			(stroke
				(width 0)
				(type default)
			)
			(fill no)
			(layer "F.CrtYd")
		)
		(fp_line
			(start 0.2794 -0.1016)
			(end -0.2794 -0.1016)
			(stroke
				(width 0.1)
				(type default)
			)
			(layer "F.Fab")
		)
		(fp_line
			(start -0.2794 -0.1016)
			(end -0.2794 0.9906)
			(stroke
				(width 0.1)
				(type default)
			)
			(layer "F.Fab")
		)
		(fp_line
			(start 0.2794 0.9906)
			(end 0.2794 -0.1016)
			(stroke
				(width 0.1)
				(type default)
			)
			(layer "F.Fab")
		)
		(fp_line
			(start -0.2794 0.9906)
			(end 0.2794 0.9906)
			(stroke
				(width 0.1)
				(type default)
			)
			(layer "F.Fab")
		)
		(pad "1" smd rect
			(at 0 0 90)
			(size 0.508 0.508)
			(layers "F.Cu" "F.Mask" "F.Paste")
			(net "P3V3_STBY")
		)
		(pad "2" smd rect
			(at 0 0.889 90)
			(size 0.508 0.508)
			(layers "F.Cu" "F.Mask" "F.Paste")
			(net "SMB_HOST_STBY_LVC3_SCL_R")
		)
		(zone
			(layer "F.Cu")
			(hatch none 0.5)
			(connect_pads
				(clearance 0)
			)
			(min_thickness 0.25)
			(keepout
				(tracks allowed)
				(vias not_allowed)
				(pads allowed)
				(copperpour not_allowed)
				(footprints allowed)
			)
			(placement
				(enabled no)
				(sheetname "")
			)
			(fill
				(thermal_gap 0.5)
				(thermal_bridge_width 0.5)
				(island_removal_mode 0)
			)
			(polygon
				(pts
					(xy 401.955 -34.172652) (xy 401.955 -34.680652) (xy 402.336 -34.680652) (xy 402.336 -34.172652)
				)
			)
		)
		(zone
			(layer "F.Cu")
			(hatch none 0.5)
			(connect_pads
				(clearance 0)
			)
			(min_thickness 0.25)
			(keepout
				(tracks not_allowed)
				(vias allowed)
				(pads allowed)
				(copperpour not_allowed)
				(footprints allowed)
			)
			(placement
				(enabled no)
				(sheetname "")
			)
			(fill
				(thermal_gap 0.5)
				(thermal_bridge_width 0.5)
				(island_removal_mode 0)
			)
			(polygon
				(pts
					(xy 402.336 -34.172652) (xy 402.336 -34.680652) (xy 401.955 -34.680652) (xy 401.955 -34.172652)
				)
			)
		)
	)
	(footprint ""
		(layer "F.Cu")
		(at 171.242736 -54.10073 180)
		(property "Reference" "L4E2"
			(at 3.378708 -4.251706 180)
			(unlocked yes)
			(layer "F.SilkS")
			(effects
				(font
					(size 0.4064 0.254)
					(thickness 0.1524)
				)
			)
		)
		(property "Value" ""
			(at 0 0 180)
			(layer "F.Fab")
			(effects
				(font
					(size 1.27 1.27)
				)
			)
		)
		(duplicate_pad_numbers_are_jumpers no)
		(fp_line
			(start 8.3693 3.199892)
			(end -1.1303 3.199892)
			(stroke
				(width 0.1524)
				(type default)
			)
			(layer "F.SilkS")
		)
		(fp_line
			(start 8.3693 1.6637)
			(end 8.3693 3.199892)
			(stroke
				(width 0.1524)
				(type default)
			)
			(layer "F.SilkS")
		)
		(fp_line
			(start 8.3693 -3.199892)
			(end 8.3693 -1.6637)
			(stroke
				(width 0.1524)
				(type default)
			)
			(layer "F.SilkS")
		)
		(fp_line
			(start -1.1303 3.199892)
			(end -1.1303 1.6637)
			(stroke
				(width 0.1524)
				(type default)
			)
			(layer "F.SilkS")
		)
		(fp_line
			(start -1.1303 -1.6637)
			(end -1.1303 -3.199892)
			(stroke
				(width 0.1524)
				(type default)
			)
			(layer "F.SilkS")
		)
		(fp_line
			(start -1.1303 -3.199892)
			(end 8.3693 -3.199892)
			(stroke
				(width 0.1524)
				(type default)
			)
			(layer "F.SilkS")
		)
		(fp_rect
			(start -1.1303 3.199892)
			(end 8.3693 -3.199892)
			(stroke
				(width 0)
				(type default)
			)
			(fill no)
			(layer "F.CrtYd")
		)
		(fp_line
			(start 8.3693 3.199892)
			(end -1.1303 3.199892)
			(stroke
				(width 0.1)
				(type default)
			)
			(layer "F.Fab")
		)
		(fp_line
			(start 8.3693 -3.199892)
			(end 8.3693 3.199892)
			(stroke
				(width 0.1)
				(type default)
			)
			(layer "F.Fab")
		)
		(fp_line
			(start -1.1303 3.199892)
			(end -1.1303 -3.199892)
			(stroke
				(width 0.1)
				(type default)
			)
			(layer "F.Fab")
		)
		(fp_line
			(start -1.1303 -3.199892)
			(end 8.3693 -3.199892)
			(stroke
				(width 0.1)
				(type default)
			)
			(layer "F.Fab")
		)
		(pad "1" smd rect
			(at 0 0 180)
			(size 3.683 2.667)
			(layers "F.Cu" "F.Mask" "F.Paste")
			(net "VR_PVCCIO_CPU1_PH1_SW")
		)
		(pad "2" smd rect
			(at 7.239 0 180)
			(size 3.683 2.667)
			(layers "F.Cu" "F.Mask" "F.Paste")
			(net "PVCCIO_CPU1")
		)
	)
	(footprint ""
		(layer "F.Cu")
		(at 87.158068 -149.8092 -90)
		(property "Reference" "C2A3"
			(at 1.848866 0.752348 270)
			(unlocked yes)
			(layer "F.SilkS")
			(effects
				(font
					(size 1.27 0.9652)
					(thickness 0.1524)
				)
			)
		)
		(property "Value" ""
			(at 0 0 270)
			(layer "F.Fab")
			(effects
				(font
					(size 1.27 1.27)
				)
			)
		)
		(duplicate_pad_numbers_are_jumpers no)
		(fp_rect
			(start -0.500126 1.598422)
			(end 0.500126 -0.201422)
			(stroke
				(width 0)
				(type default)
			)
			(fill no)
			(layer "F.CrtYd")
		)
		(fp_line
			(start -0.500126 1.598422)
			(end -0.500126 -0.201422)
			(stroke
				(width 0.1)
				(type default)
			)
			(layer "F.Fab")
		)
		(fp_line
			(start 0.500126 1.598422)
			(end -0.500126 1.598422)
			(stroke
				(width 0.1)
				(type default)
			)
			(layer "F.Fab")
		)
		(fp_line
			(start -0.500126 -0.201422)
			(end 0.500126 -0.201422)
			(stroke
				(width 0.1)
				(type default)
			)
			(layer "F.Fab")
		)
		(fp_line
			(start 0.500126 -0.201422)
			(end 0.500126 1.598422)
			(stroke
				(width 0.1)
				(type default)
			)
			(layer "F.Fab")
		)
		(pad "1" smd rect
			(at 0 0 180)
			(size 0.889 0.9906)
			(layers "F.Cu" "F.Mask" "F.Paste")
			(net "PVDDQ_KLM")
		)
		(pad "2" smd rect
			(at 0 1.397 180)
			(size 0.889 0.9906)
			(layers "F.Cu" "F.Mask" "F.Paste")
			(net "GND")
		)
		(zone
			(layer "F.Cu")
			(hatch none 0.5)
			(connect_pads
				(clearance 0)
			)
			(min_thickness 0.25)
			(keepout
				(tracks not_allowed)
				(vias allowed)
				(pads allowed)
				(copperpour not_allowed)
				(footprints allowed)
			)
			(placement
				(enabled no)
				(sheetname "")
			)
			(fill
				(thermal_gap 0.5)
				(thermal_bridge_width 0.5)
				(island_removal_mode 0)
			)
			(polygon
				(pts
					(xy 86.205568 -150.3045) (xy 86.205568 -149.3139) (xy 86.713568 -149.3139) (xy 86.713568 -150.3045)
				)
			)
		)
		(zone
			(layer "F.Cu")
			(hatch none 0.5)
			(connect_pads
				(clearance 0)
			)
			(min_thickness 0.25)
			(keepout
				(tracks allowed)
				(vias not_allowed)
				(pads allowed)
				(copperpour not_allowed)
				(footprints allowed)
			)
			(placement
				(enabled no)
				(sheetname "")
			)
			(fill
				(thermal_gap 0.5)
				(thermal_bridge_width 0.5)
				(island_removal_mode 0)
			)
			(polygon
				(pts
					(xy 86.205568 -150.3045) (xy 86.205568 -149.3139) (xy 86.713568 -149.3139) (xy 86.713568 -150.3045)
				)
			)
		)
	)
	(footprint ""
		(layer "F.Cu")
		(at 22.225 -77.724 90)
		(property "Reference" "R1D30"
			(at 0 0 90)
			(layer "F.SilkS")
			(hide yes)
			(effects
				(font
					(size 1.27 1.27)
				)
			)
		)
		(property "Value" ""
			(at 0 0 90)
			(layer "F.Fab")
			(effects
				(font
					(size 1.27 1.27)
				)
			)
		)
		(duplicate_pad_numbers_are_jumpers no)
		(fp_poly
			(pts
				(xy -0.2794 -0.1016) (xy 0.2794 -0.1016) (xy 0.2794 0.9906) (xy -0.2794 0.9906)
			)
			(stroke
				(width 0)
				(type default)
			)
			(fill no)
			(layer "F.CrtYd")
		)
		(fp_line
			(start 0.2794 -0.1016)
			(end -0.2794 -0.1016)
			(stroke
				(width 0.1)
				(type default)
			)
			(layer "F.Fab")
		)
		(fp_line
			(start -0.2794 -0.1016)
			(end -0.2794 0.9906)
			(stroke
				(width 0.1)
				(type default)
			)
			(layer "F.Fab")
		)
		(fp_line
			(start 0.2794 0.9906)
			(end 0.2794 -0.1016)
			(stroke
				(width 0.1)
				(type default)
			)
			(layer "F.Fab")
		)
		(fp_line
			(start -0.2794 0.9906)
			(end 0.2794 0.9906)
			(stroke
				(width 0.1)
				(type default)
			)
			(layer "F.Fab")
		)
		(pad "1" smd rect
			(at 0 0 90)
			(size 0.508 0.508)
			(layers "F.Cu" "F.Mask" "F.Paste")
			(net "IRQ_HSC_FAULT_R_N")
		)
		(pad "2" smd rect
			(at 0 0.889 90)
			(size 0.508 0.508)
			(layers "F.Cu" "F.Mask" "F.Paste")
			(net "IRQ_HSC_FAULT_N")
		)
		(zone
			(layer "F.Cu")
			(hatch none 0.5)
			(connect_pads
				(clearance 0)
			)
			(min_thickness 0.25)
			(keepout
				(tracks allowed)
				(vias not_allowed)
				(pads allowed)
				(copperpour not_allowed)
				(footprints allowed)
			)
			(placement
				(enabled no)
				(sheetname "")
			)
			(fill
				(thermal_gap 0.5)
				(thermal_bridge_width 0.5)
				(island_removal_mode 0)
			)
			(polygon
				(pts
					(xy 22.479 -77.47) (xy 22.479 -77.978) (xy 22.86 -77.978) (xy 22.86 -77.47)
				)
			)
		)
		(zone
			(layer "F.Cu")
			(hatch none 0.5)
			(connect_pads
				(clearance 0)
			)
			(min_thickness 0.25)
			(keepout
				(tracks not_allowed)
				(vias allowed)
				(pads allowed)
				(copperpour not_allowed)
				(footprints allowed)
			)
			(placement
				(enabled no)
				(sheetname "")
			)
			(fill
				(thermal_gap 0.5)
				(thermal_bridge_width 0.5)
				(island_removal_mode 0)
			)
			(polygon
				(pts
					(xy 22.86 -77.47) (xy 22.86 -77.978) (xy 22.479 -77.978) (xy 22.479 -77.47)
				)
			)
		)
	)
	(footprint ""
		(layer "F.Cu")
		(at 189.2808 -68.2498 180)
		(property "Reference" "CF3"
			(at 0 0 180)
			(layer "F.SilkS")
			(hide yes)
			(effects
				(font
					(size 1.27 1.27)
				)
			)
		)
		(property "Value" "*"
			(at 1.1811 -2.8194 180)
			(unlocked yes)
			(layer "F.Fab")
			(hide yes)
			(effects
				(font
					(size 1.27 1.016)
					(thickness 0.1524)
				)
			)
		)
		(property "Device Type" "SC22P50V2JN-4GP_SMD-BCG-SC22P5A"
			(at 1.1811 -4.3434 180)
			(unlocked yes)
			(layer "F.Fab")
			(hide yes)
			(effects
				(font
					(size 1.27 1.016)
					(thickness 0.1524)
				)
			)
		)
		(duplicate_pad_numbers_are_jumpers no)
		(fp_rect
			(start -0.4318 0.9525)
			(end 0.4318 -0.9525)
			(stroke
				(width 0)
				(type default)
			)
			(fill no)
			(layer "F.CrtYd")
		)
		(fp_rect
			(start -0.4318 0.9525)
			(end 0.4318 -0.9525)
			(stroke
				(width 0)
				(type default)
			)
			(fill no)
			(layer "F.Fab")
		)
		(pad "1" smd custom
			(at 0 -0.4445 180)
			(size 0.1524 0.1524)
			(layers "F.Cu" "F.Mask" "F.Paste")
			(net "VR_PVCCIN_CPU0_AIREF3")
			(options
				(clearance outline)
				(anchor circle)
			)
			(primitives
				(gr_poly
					(pts
						(arc
							(start 0.3048 -0.2032)
							(mid 0.275042 -0.275042)
							(end 0.2032 -0.3048)
						)
						(arc
							(start -0.2032 -0.3048)
							(mid -0.275042 -0.275042)
							(end -0.3048 -0.2032)
						)
						(arc
							(start -0.3048 0.2032)
							(mid -0.275042 0.275042)
							(end -0.2032 0.3048)
						)
						(arc
							(start 0.2032 0.3048)
							(mid 0.275042 0.275042)
							(end 0.3048 0.2032)
						)
					)
					(width 0)
					(fill yes)
				)
			)
		)
		(pad "2" smd custom
			(at 0 0.4445 180)
			(size 0.1524 0.1524)
			(layers "F.Cu" "F.Mask" "F.Paste")
			(net "ISENSE_PVCCIN_CPU0_PH3_IMON")
			(options
				(clearance outline)
				(anchor circle)
			)
			(primitives
				(gr_poly
					(pts
						(arc
							(start 0.3048 -0.2032)
							(mid 0.275042 -0.275042)
							(end 0.2032 -0.3048)
						)
						(arc
							(start -0.2032 -0.3048)
							(mid -0.275042 -0.275042)
							(end -0.3048 -0.2032)
						)
						(arc
							(start -0.3048 0.2032)
							(mid -0.275042 0.275042)
							(end -0.2032 0.3048)
						)
						(arc
							(start 0.2032 0.3048)
							(mid 0.275042 0.275042)
							(end 0.3048 0.2032)
						)
					)
					(width 0)
					(fill yes)
				)
			)
		)
	)
)
